# T6G (Grand Teton) — schematic netlist excerpt (pin names and nets, part order shuffled) for the footprints in the layout excerpt that follows; sources: Cadence DE-HDL packaged netlist, KiCad conversion of 04192023_DAF0TMB3IC0_F0TG_MB_C_brd_V02_OCP.brd

J68  SCONN288_DDR506112002KQ  IO  pkg DDR288S_1-1VXC  page 95
  VIN_BULK0  = P12V_MEM_CPU0
  RFU0  = NC
  VIN_MGMT  = P3V3_AUX
  HSCL  = I3C_SPD_DDRJ_CPU0_SCL
  HSDA  = I3C_SPD_DDRJ_CPU0_SDA
  VSS0  = GND
  DQ0_A  = M_J_CPU0_SA_DQ<0>
  VSS1  = GND
  DQ1_A  = M_J_CPU0_SA_DQ<1>
  VSS2  = GND
  DQS0_A_T  = M_J_CPU0_SA_DQS_DP<0>
  DQS0_A_C  = M_J_CPU0_SA_DQS_DN<0>
  VSS3  = GND
  DQ4_A  = M_J_CPU0_SA_DQ<4>
  VSS4  = GND
  DQ5_A  = M_J_CPU0_SA_DQ<5>
  VSS5  = GND
  DQ8_A  = M_J_CPU0_SA_DQ<8>
  VSS6  = GND
  DQ9_A  = M_J_CPU0_SA_DQ<9>
  VSS7  = GND
  DQS1_A_T  = M_J_CPU0_SA_DQS_DP<1>
  DQS1_A_C  = M_J_CPU0_SA_DQS_DN<1>
  VSS8  = GND
  DQ12_A  = M_J_CPU0_SA_DQ<12>
  VSS9  = GND
  DQ13_A  = M_J_CPU0_SA_DQ<13>
  VSS10  = GND
  DQ16_A  = M_J_CPU0_SA_DQ<16>
  VSS11  = GND
  DQ17_A  = M_J_CPU0_SA_DQ<17>
  VSS12  = GND
  DQS2_A_T  = M_J_CPU0_SA_DQS_DP<2>
  DQS2_A_C  = M_J_CPU0_SA_DQS_DN<2>
  VSS13  = GND
  DQ20_A  = M_J_CPU0_SA_DQ<20>
  VSS14  = GND
  DQ21_A  = M_J_CPU0_SA_DQ<21>
  VSS15  = GND
  DQ24_A  = M_J_CPU0_SA_DQ<24>
  VSS16  = GND
  DQ25_A  = M_J_CPU0_SA_DQ<25>
  VSS17  = GND
  DQS3_A_T  = M_J_CPU0_SA_DQS_DP<3>
  DQS3_A_C  = M_J_CPU0_SA_DQS_DN<3>
  VSS18  = GND
  DQ28_A  = M_J_CPU0_SA_DQ<28>
  VSS19  = GND
  DQ29_A  = M_J_CPU0_SA_DQ<29>
  VSS20  = GND
  CB0_A  = M_J_CPU0_SA_CB<0>
  VSS21  = GND
  CB1_A  = M_J_CPU0_SA_CB<1>
  VSS22  = GND
  DQS4_A_T  = M_J_CPU0_SA_DQS_DP<4>
  DQS4_A_C  = M_J_CPU0_SA_DQS_DN<4>
  VSS23  = GND
  CB4_A  = M_J_CPU0_SA_CB<4>
  VSS24  = GND
  CB5_A  = M_J_CPU0_SA_CB<5>
  VSS25  = GND
  ALERT_N  = M_J_CPU0_ALERT_N
  VSS26  = GND
  CS0_A_N  = M_J_CPU0_SA_CS_N<0>
  VSS27  = GND
  CA0_A  = M_J_CPU0_SA_CA<0>
  VSS28  = GND
  CA2_A  = M_J_CPU0_SA_CA<2>
  VSS29  = GND
  CA4_A  = M_J_CPU0_SA_CA<4>
  VSS30  = GND
  CA6_A  = M_J_CPU0_SA_CA<6>
  VSS31  = GND
  PAR_A  = M_J_CPU0_SA_PAR
  VSS32  = GND
  CA0_B  = M_J_CPU0_SB_CA<0>
  VSS33  = GND
  CA2_B  = M_J_CPU0_SB_CA<2>
  VSS34  = GND
  CA4_B  = M_J_CPU0_SB_CA<4>
  VSS35  = GND
  CA6_B  = M_J_CPU0_SB_CA<6>
  VSS36  = GND
  CS0_B_N  = M_J_CPU0_SB_CS_N<0>
  VSS37  = GND
  \lbd||rsp_a_n\  = M_J_CPU0_SA_RSP<0>
  \lbs||rsp_b_n\  = M_J_CPU0_SB_RSP<0>
  VSS38  = GND
  CB4_B  = M_J_CPU0_SB_CB<4>
  VSS39  = GND
  CB5_B  = M_J_CPU0_SB_CB<5>
  VSS40  = GND
  \dqs9_b_t||tdqs9_b_t||dbi4_b_n\  = M_J_CPU0_SB_DQS_DP<9>
  \dqs9_b_c||tdqs9_b_c\  = M_J_CPU0_SB_DQS_DN<9>
  VSS41  = GND
  CB0_B  = M_J_CPU0_SB_CB<0>
  VSS42  = GND
  CB1_B  = M_J_CPU0_SB_CB<1>
  VSS43  = GND
  DQ0_B  = M_J_CPU0_SB_DQ<0>
  VSS44  = GND
  DQ1_B  = M_J_CPU0_SB_DQ<1>
  VSS45  = GND
  DQS0_B_T  = M_J_CPU0_SB_DQS_DP<0>
  DQS0_B_C  = M_J_CPU0_SB_DQS_DN<0>
  VSS46  = GND
  DQ4_B  = M_J_CPU0_SB_DQ<4>
  VSS47  = GND
  DQ5_B  = M_J_CPU0_SB_DQ<5>
  VSS48  = GND
  DQ8_B  = M_J_CPU0_SB_DQ<8>
  VSS49  = GND
  DQ9_B  = M_J_CPU0_SB_DQ<9>
  VSS50  = GND
  DQS1_B_T  = M_J_CPU0_SB_DQS_DP<1>
  DQS1_B_C  = M_J_CPU0_SB_DQS_DN<1>
  VSS51  = GND
  DQ12_B  = M_J_CPU0_SB_DQ<12>
  VSS52  = GND
  DQ13_B  = M_J_CPU0_SB_DQ<13>
  VSS53  = GND
  DQ16_B  = M_J_CPU0_SB_DQ<16>
  VSS54  = GND
  DQ17_B  = M_J_CPU0_SB_DQ<17>
  VSS55  = GND
  DQS2_B_T  = M_J_CPU0_SB_DQS_DP<2>
  DQS2_B_C  = M_J_CPU0_SB_DQS_DN<2>
  VSS56  = GND
  DQ20_B  = M_J_CPU0_SB_DQ<20>
  VSS57  = GND
  DQ21_B  = M_J_CPU0_SB_DQ<21>
  VSS58  = GND
  DQ24_B  = M_J_CPU0_SB_DQ<24>
  VSS59  = GND
  DQ25_B  = M_J_CPU0_SB_DQ<25>
  VSS60  = GND
  DQS3_B_T  = M_J_CPU0_SB_DQS_DP<3>
  DQS3_B_C  = M_J_CPU0_SB_DQS_DN<3>
  VSS61  = GND
  DQ28_B  = M_J_CPU0_SB_DQ<28>
  VSS62  = GND
  DQ29_B  = M_J_CPU0_SB_DQ<29>
  VSS63  = GND
  RFU1  = NC
  VIN_BULK1  = P12V_MEM_CPU0
  VIN_BULK2  = P12V_MEM_CPU0
  \pwr_good||fail_n\  = PWRGD_CHJ_CPU0_DIMM
  HAS  = PD_CHJ_CPU0_DIMM_SAA
  RFU2  = NC
  RFU3  = NC
  VSS64  = GND
  DQ2_A  = M_J_CPU0_SA_DQ<2>
  VSS65  = GND
  DQ3_A  = M_J_CPU0_SA_DQ<3>
  VSS66  = GND
  \dqs5_a_c||tdqs5_a_c||dqs5_a_t||tdqs5_a_t\  = M_J_CPU0_SA_DQS_DN<5>
  \dqs5_a_t||tdqs5_a_t\  = M_J_CPU0_SA_DQS_DP<5>
  VSS67  = GND
  DQ6_A  = M_J_CPU0_SA_DQ<6>
  VSS68  = GND
  DQ7_A  = M_J_CPU0_SA_DQ<7>
  VSS69  = GND
  DQ10_A  = M_J_CPU0_SA_DQ<10>
  VSS70  = GND
  DQ11_A  = M_J_CPU0_SA_DQ<11>
  VSS71  = GND
  \dqs6_a_c||tdqs6_a_c||dqs6_a_t||tdqs6_a_t\  = M_J_CPU0_SA_DQS_DN<6>
  \dqs6_a_t||tdqs6_a_t\  = M_J_CPU0_SA_DQS_DP<6>
  VSS72  = GND
  DQ14_A  = M_J_CPU0_SA_DQ<14>
  VSS73  = GND
  DQ15_A  = M_J_CPU0_SA_DQ<15>
  VSS74  = GND
  DQ18_A  = M_J_CPU0_SA_DQ<18>
  VSS75  = GND
  DQ19_A  = M_J_CPU0_SA_DQ<19>
  VSS76  = GND
  \dqs7_a_c||tdqs7_a_c\  = M_J_CPU0_SA_DQS_DN<7>
  \dqs7_a_t||tdqs7_a_t\  = M_J_CPU0_SA_DQS_DP<7>
  VSS77  = GND
  DQ22_A  = M_J_CPU0_SA_DQ<22>
  VSS78  = GND
  DQ23_A  = M_J_CPU0_SA_DQ<23>
  VSS79  = GND
  DQ26_A  = M_J_CPU0_SA_DQ<26>
  VSS80  = GND
  DQ27_A  = M_J_CPU0_SA_DQ<27>
  VSS81  = GND
  \dqs8_a_c||tdqs8_a_c\  = M_J_CPU0_SA_DQS_DN<8>
  \dqs8_a_t||tdqs8_a_t\  = M_J_CPU0_SA_DQS_DP<8>
  VSS82  = GND
  DQ30_A  = M_J_CPU0_SA_DQ<30>
  VSS83  = GND
  DQ31_A  = M_J_CPU0_SA_DQ<31>
  VSS84  = GND
  CB2_A  = M_J_CPU0_SA_CB<2>
  VSS85  = GND
  CB3_A  = M_J_CPU0_SA_CB<3>
  VSS86  = GND
  \dqs9_a_c||tdqs9_a_c\  = M_J_CPU0_SA_DQS_DN<9>
  \dqs9_a_t||tdqs9_a_t\  = M_J_CPU0_SA_DQS_DP<9>
  VSS87  = GND
  CB6_A  = M_J_CPU0_SA_CB<6>
  VSS88  = GND
  CB7_A  = M_J_CPU0_SA_CB<7>
  VSS89  = GND
  RESET_N  = M_J_CPU0_RESET_N
  VSS90  = GND
  CS1_A_N  = M_J_CPU0_SA_CS_N<1>
  VSS91  = GND
  CA1_A  = M_J_CPU0_SA_CA<1>
  VSS92  = GND
  CA3_A  = M_J_CPU0_SA_CA<3>
  VSS93  = GND
  CA5_A  = M_J_CPU0_SA_CA<5>
  VSS94  = GND
  CK_T  = M_J_CPU0_CLK_DP<0>
  CK_C  = M_J_CPU0_CLK_DN<0>
  VSS95  = GND
  RFU4  = NC
  CA1_B  = M_J_CPU0_SB_CA<1>
  VSS96  = GND
  CA3_B  = M_J_CPU0_SB_CA<3>
  VSS97  = GND
  CA5_B  = M_J_CPU0_SB_CA<5>
  VSS98  = GND
  PAR_B  = M_J_CPU0_SB_PAR
  VSS99  = GND
  CS1_B_N  = M_J_CPU0_SB_CS_N<1>
  VSS100  = GND
  RFU5  = NC
  RFU6  = NC
  VSS101  = GND
  CB6_B  = M_J_CPU0_SB_CB<6>
  VSS102  = GND
  CB7_B  = M_J_CPU0_SB_CB<7>
  VSS103  = GND
  DQS4_B_C  = M_J_CPU0_SB_DQS_DN<4>
  DQS4_B_T  = M_J_CPU0_SB_DQS_DP<4>
  VSS104  = GND
  CB2_B  = M_J_CPU0_SB_CB<2>
  VSS105  = GND
  CB3_B  = M_J_CPU0_SB_CB<3>
  VSS106  = GND
  DQ2_B  = M_J_CPU0_SB_DQ<2>
  VSS107  = GND
  DQ3_B  = M_J_CPU0_SB_DQ<3>
  VSS108  = GND
  \dqs5_b_c||tdqs5_b_c\  = M_J_CPU0_SB_DQS_DN<5>
  \dqs5_b_t||tdqs5_b_t\  = M_J_CPU0_SB_DQS_DP<5>
  VSS109  = GND
  DQ6_B  = M_J_CPU0_SB_DQ<6>
  VSS110  = GND
  DQ7_B  = M_J_CPU0_SB_DQ<7>
  VSS111  = GND
  DQ10_B  = M_J_CPU0_SB_DQ<10>
  VSS112  = GND
  DQ11_B  = M_J_CPU0_SB_DQ<11>
  VSS113  = GND
  \dqs6_b_c||tdqs6_b_c\  = M_J_CPU0_SB_DQS_DN<6>
  \dqs6_b_t||tdqs6_b_t\  = M_J_CPU0_SB_DQS_DP<6>
  VSS114  = GND
  DQ14_B  = M_J_CPU0_SB_DQ<14>
  VSS115  = GND
  DQ15_B  = M_J_CPU0_SB_DQ<15>
  VSS116  = GND
  DQ18_B  = M_J_CPU0_SB_DQ<18>
  VSS117  = GND
  DQ19_B  = M_J_CPU0_SB_DQ<19>
  VSS118  = GND
  \dqs7_b_c||tdqs7_b_c\  = M_J_CPU0_SB_DQS_DN<7>
  \dqs7_b_t||tdqs7_b_t\  = M_J_CPU0_SB_DQS_DP<7>
  VSS119  = GND
  DQ22_B  = M_J_CPU0_SB_DQ<22>
  VSS120  = GND
  DQ23_B  = M_J_CPU0_SB_DQ<23>
  VSS121  = GND
  DQ26_B  = M_J_CPU0_SB_DQ<26>
  VSS122  = GND
  DQ27_B  = M_J_CPU0_SB_DQ<27>
  VSS123  = GND
  \dqs8_b_c||tdqs8_b_c\  = M_J_CPU0_SB_DQS_DN<8>
  \dqs8_b_t||tdqs8_b_t\  = M_J_CPU0_SB_DQS_DP<8>
  VSS124  = GND
  DQ30_B  = M_J_CPU0_SB_DQ<30>
  VSS125  = GND
  DQ31_B  = M_J_CPU0_SB_DQ<31>
  VSS126  = GND
  G1  = GND
  G2  = GND
  G3  = GND

(kicad_pcb
	(version 20260206)
	(generator "pcbnew")
	(generator_version "10.0")
	(general
		(thickness 1.6)
		(legacy_teardrops no)
	)
	(paper "A4")
	(title_block
		(title "04192023_DAF0TMB3IC0_F0TG_MB_C_brd_V02_OCP.brd")
		(comment 1 "Grand Teton / footprint 802 of 8354 (J68), pads 1-45 of 291")
	)
	(layers
		(0 "F.Cu" signal "TOP")
		(4 "In1.Cu" signal "GND")
		(6 "In2.Cu" signal "IN1")
		(8 "In3.Cu" signal "GND1")
		(10 "In4.Cu" signal "IN2")
		(12 "In5.Cu" signal "GND2")
		(14 "In6.Cu" signal "IN3")
		(16 "In7.Cu" signal "GND3")
		(18 "In8.Cu" signal "VCC")
		(20 "In9.Cu" signal "VCC1")
		(22 "In10.Cu" signal "GND4")
		(24 "In11.Cu" signal "IN4")
		(26 "In12.Cu" signal "GND5")
		(28 "In13.Cu" signal "IN5")
		(30 "In14.Cu" signal "GND6")
		(32 "In15.Cu" signal "IN6")
		(34 "In16.Cu" signal "GND7")
		(2 "B.Cu" signal "BOTTOM")
		(9 "F.Adhes" user "F.Adhesive")
		(11 "B.Adhes" user "B.Adhesive")
		(13 "F.Paste" user "Package Geometry/Pastemask Top")
		(15 "B.Paste" user "Package Geometry/Pastemask Bottom")
		(5 "F.SilkS" user "Ref Des/Silkscreen Top")
		(7 "B.SilkS" user "Ref Des/Silkscreen Bottom")
		(1 "F.Mask" user "Board Geometry/Soldermask Top")
		(3 "B.Mask" user "Board Geometry/Soldermask Bottom")
		(17 "Dwgs.User" user "User.Drawings")
		(19 "Cmts.User" user "User.Comments")
		(21 "Eco1.User" user "User.Eco1")
		(23 "Eco2.User" user "User.Eco2")
		(25 "Edge.Cuts" user "Board Geometry/Outline")
		(27 "Margin" user)
		(31 "F.CrtYd" user "Package Geometry/Place Bound Top")
		(29 "B.CrtYd" user "Package Geometry/Place Bound Bottom")
		(35 "F.Fab" user "Ref Des/Assembly Top")
		(33 "B.Fab" user "Ref Des/Assembly Bottom")
	)
	(footprint ""
		(layer "F.Cu")
		(at 437.05018 -255.560068 180)
		(property "Reference" "J68"
			(at 1.32334 -81.844388 0)
			(unlocked yes)
			(layer "F.SilkS")
			(effects
				(font
					(size 0.7874 0.5842)
					(thickness 0.1524)
				)
			)
		)
		(property "Value" ""
			(at 0 0 180)
			(layer "F.Fab")
			(effects
				(font
					(size 1.27 1.27)
				)
			)
		)
		(duplicate_pad_numbers_are_jumpers no)
		(pad "1" smd rect
			(at -2.050034 -63.324994 90)
			(size 0.519938 1.4986)
			(layers "F.Cu" "F.Mask" "F.Paste")
			(net "P12V_MEM_CPU0")
		)
		(pad "2" smd rect
			(at -2.050034 -62.47511 90)
			(size 0.519938 1.4986)
			(layers "F.Cu" "F.Mask" "F.Paste")
			(net "Net_2375")
		)
		(pad "3" smd rect
			(at -2.050034 -61.624972 90)
			(size 0.519938 1.4986)
			(layers "F.Cu" "F.Mask" "F.Paste")
			(net "P3V3_AUX")
		)
		(pad "4" smd rect
			(at -2.050034 -60.775088 90)
			(size 0.519938 1.4986)
			(layers "F.Cu" "F.Mask" "F.Paste")
			(net "I3C_SPD_DDRJ_CPU0_SCL")
		)
		(pad "5" smd rect
			(at -2.050034 -59.92495 90)
			(size 0.519938 1.4986)
			(layers "F.Cu" "F.Mask" "F.Paste")
			(net "I3C_SPD_DDRJ_CPU0_SDA")
		)
		(pad "6" smd rect
			(at -2.050034 -59.075066 90)
			(size 0.519938 1.4986)
			(layers "F.Cu" "F.Mask" "F.Paste")
			(net "GND")
		)
		(pad "7" smd rect
			(at -2.050034 -58.224928 90)
			(size 0.519938 1.4986)
			(layers "F.Cu" "F.Mask" "F.Paste")
			(net "M_J_CPU0_SA_DQ<0>")
		)
		(pad "8" smd rect
			(at -2.050034 -57.375044 90)
			(size 0.519938 1.4986)
			(layers "F.Cu" "F.Mask" "F.Paste")
			(net "GND")
		)
		(pad "9" smd rect
			(at -2.050034 -56.524906 90)
			(size 0.519938 1.4986)
			(layers "F.Cu" "F.Mask" "F.Paste")
			(net "M_J_CPU0_SA_DQ<1>")
		)
		(pad "10" smd rect
			(at -2.050034 -55.675022 90)
			(size 0.519938 1.4986)
			(layers "F.Cu" "F.Mask" "F.Paste")
			(net "GND")
		)
		(pad "11" smd rect
			(at -2.050034 -54.824884 90)
			(size 0.519938 1.4986)
			(layers "F.Cu" "F.Mask" "F.Paste")
			(net "M_J_CPU0_SA_DQS_DP<0>")
		)
		(pad "12" smd rect
			(at -2.050034 -53.975 90)
			(size 0.519938 1.4986)
			(layers "F.Cu" "F.Mask" "F.Paste")
			(net "M_J_CPU0_SA_DQS_DN<0>")
		)
		(pad "13" smd rect
			(at -2.050034 -53.125116 90)
			(size 0.519938 1.4986)
			(layers "F.Cu" "F.Mask" "F.Paste")
			(net "GND")
		)
		(pad "14" smd rect
			(at -2.050034 -52.274978 90)
			(size 0.519938 1.4986)
			(layers "F.Cu" "F.Mask" "F.Paste")
			(net "M_J_CPU0_SA_DQ<4>")
		)
		(pad "15" smd rect
			(at -2.050034 -51.425094 90)
			(size 0.519938 1.4986)
			(layers "F.Cu" "F.Mask" "F.Paste")
			(net "GND")
		)
		(pad "16" smd rect
			(at -2.050034 -50.574956 90)
			(size 0.519938 1.4986)
			(layers "F.Cu" "F.Mask" "F.Paste")
			(net "M_J_CPU0_SA_DQ<5>")
		)
		(pad "17" smd rect
			(at -2.050034 -49.725072 90)
			(size 0.519938 1.4986)
			(layers "F.Cu" "F.Mask" "F.Paste")
			(net "GND")
		)
		(pad "18" smd rect
			(at -2.050034 -48.874934 90)
			(size 0.519938 1.4986)
			(layers "F.Cu" "F.Mask" "F.Paste")
			(net "M_J_CPU0_SA_DQ<8>")
		)
		(pad "19" smd rect
			(at -2.050034 -48.02505 90)
			(size 0.519938 1.4986)
			(layers "F.Cu" "F.Mask" "F.Paste")
			(net "GND")
		)
		(pad "20" smd rect
			(at -2.050034 -47.174912 90)
			(size 0.519938 1.4986)
			(layers "F.Cu" "F.Mask" "F.Paste")
			(net "M_J_CPU0_SA_DQ<9>")
		)
		(pad "21" smd rect
			(at -2.050034 -46.325028 90)
			(size 0.519938 1.4986)
			(layers "F.Cu" "F.Mask" "F.Paste")
			(net "GND")
		)
		(pad "22" smd rect
			(at -2.050034 -45.47489 90)
			(size 0.519938 1.4986)
			(layers "F.Cu" "F.Mask" "F.Paste")
			(net "M_J_CPU0_SA_DQS_DP<1>")
		)
		(pad "23" smd rect
			(at -2.050034 -44.625006 90)
			(size 0.519938 1.4986)
			(layers "F.Cu" "F.Mask" "F.Paste")
			(net "M_J_CPU0_SA_DQS_DN<1>")
		)
		(pad "24" smd rect
			(at -2.050034 -43.775122 90)
			(size 0.519938 1.4986)
			(layers "F.Cu" "F.Mask" "F.Paste")
			(net "GND")
		)
		(pad "25" smd rect
			(at -2.050034 -42.924984 90)
			(size 0.519938 1.4986)
			(layers "F.Cu" "F.Mask" "F.Paste")
			(net "M_J_CPU0_SA_DQ<12>")
		)
		(pad "26" smd rect
			(at -2.050034 -42.0751 90)
			(size 0.519938 1.4986)
			(layers "F.Cu" "F.Mask" "F.Paste")
			(net "GND")
		)
		(pad "27" smd rect
			(at -2.050034 -41.224962 90)
			(size 0.519938 1.4986)
			(layers "F.Cu" "F.Mask" "F.Paste")
			(net "M_J_CPU0_SA_DQ<13>")
		)
		(pad "28" smd rect
			(at -2.050034 -40.375078 90)
			(size 0.519938 1.4986)
			(layers "F.Cu" "F.Mask" "F.Paste")
			(net "GND")
		)
		(pad "29" smd rect
			(at -2.050034 -39.52494 90)
			(size 0.519938 1.4986)
			(layers "F.Cu" "F.Mask" "F.Paste")
			(net "M_J_CPU0_SA_DQ<16>")
		)
		(pad "30" smd rect
			(at -2.050034 -38.675056 90)
			(size 0.519938 1.4986)
			(layers "F.Cu" "F.Mask" "F.Paste")
			(net "GND")
		)
		(pad "31" smd rect
			(at -2.050034 -37.824918 90)
			(size 0.519938 1.4986)
			(layers "F.Cu" "F.Mask" "F.Paste")
			(net "M_J_CPU0_SA_DQ<17>")
		)
		(pad "32" smd rect
			(at -2.050034 -36.975034 90)
			(size 0.519938 1.4986)
			(layers "F.Cu" "F.Mask" "F.Paste")
			(net "GND")
		)
		(pad "33" smd rect
			(at -2.050034 -36.124896 90)
			(size 0.519938 1.4986)
			(layers "F.Cu" "F.Mask" "F.Paste")
			(net "M_J_CPU0_SA_DQS_DP<2>")
		)
		(pad "34" smd rect
			(at -2.050034 -35.275012 90)
			(size 0.519938 1.4986)
			(layers "F.Cu" "F.Mask" "F.Paste")
			(net "M_J_CPU0_SA_DQS_DN<2>")
		)
		(pad "35" smd rect
			(at -2.050034 -34.425128 90)
			(size 0.519938 1.4986)
			(layers "F.Cu" "F.Mask" "F.Paste")
			(net "GND")
		)
		(pad "36" smd rect
			(at -2.050034 -33.57499 90)
			(size 0.519938 1.4986)
			(layers "F.Cu" "F.Mask" "F.Paste")
			(net "M_J_CPU0_SA_DQ<20>")
		)
		(pad "37" smd rect
			(at -2.050034 -32.725106 90)
			(size 0.519938 1.4986)
			(layers "F.Cu" "F.Mask" "F.Paste")
			(net "GND")
		)
		(pad "38" smd rect
			(at -2.050034 -31.874968 90)
			(size 0.519938 1.4986)
			(layers "F.Cu" "F.Mask" "F.Paste")
			(net "M_J_CPU0_SA_DQ<21>")
		)
		(pad "39" smd rect
			(at -2.050034 -31.025084 90)
			(size 0.519938 1.4986)
			(layers "F.Cu" "F.Mask" "F.Paste")
			(net "GND")
		)
		(pad "40" smd rect
			(at -2.050034 -30.174946 90)
			(size 0.519938 1.4986)
			(layers "F.Cu" "F.Mask" "F.Paste")
			(net "M_J_CPU0_SA_DQ<24>")
		)
		(pad "41" smd rect
			(at -2.050034 -29.325062 90)
			(size 0.519938 1.4986)
			(layers "F.Cu" "F.Mask" "F.Paste")
			(net "GND")
		)
		(pad "42" smd rect
			(at -2.050034 -28.474924 90)
			(size 0.519938 1.4986)
			(layers "F.Cu" "F.Mask" "F.Paste")
			(net "M_J_CPU0_SA_DQ<25>")
		)
		(pad "43" smd rect
			(at -2.050034 -27.62504 90)
			(size 0.519938 1.4986)
			(layers "F.Cu" "F.Mask" "F.Paste")
			(net "GND")
		)
		(pad "44" smd rect
			(at -2.050034 -26.774902 90)
			(size 0.519938 1.4986)
			(layers "F.Cu" "F.Mask" "F.Paste")
			(net "M_J_CPU0_SA_DQS_DP<3>")
		)
		(pad "45" smd rect
			(at -2.050034 -25.925018 90)
			(size 0.519938 1.4986)
			(layers "F.Cu" "F.Mask" "F.Paste")
			(net "M_J_CPU0_SA_DQS_DN<3>")
		)
	)
)
